(kicad_pcb
	(version 20260206)
	(generator "pcbnew")
	(generator_version "10.0")
	(general
		(thickness 1.6)
		(legacy_teardrops no)
	)
	(paper "A4")
	(title_block
		(title "01162023_DA0F0TEBIF0_F0T_Expander_BD_F_brd_V02_OCP.brd")
		(comment 1 "Grand Teton / footprints 3002-3009 of 9728")
	)
	(layers
		(0 "F.Cu" signal "TOP")
		(4 "In1.Cu" signal "GND")
		(6 "In2.Cu" signal "VCC")
		(8 "In3.Cu" signal "VCC1")
		(10 "In4.Cu" signal "GND1")
		(12 "In5.Cu" signal "IN1")
		(14 "In6.Cu" signal "GND2")
		(16 "In7.Cu" signal "IN2")
		(18 "In8.Cu" signal "GND3")
		(20 "In9.Cu" signal "IN3")
		(22 "In10.Cu" signal "GND4")
		(24 "In11.Cu" signal "IN4")
		(26 "In12.Cu" signal "GND5")
		(28 "In13.Cu" signal "IN5")
		(30 "In14.Cu" signal "GND6")
		(32 "In15.Cu" signal "IN6")
		(34 "In16.Cu" signal "GND7")
		(2 "B.Cu" signal "BOTTOM")
		(9 "F.Adhes" user "F.Adhesive")
		(11 "B.Adhes" user "B.Adhesive")
		(13 "F.Paste" user "Package Geometry/Pastemask Top")
		(15 "B.Paste" user "Package Geometry/Pastemask Bottom")
		(5 "F.SilkS" user "Ref Des/Silkscreen Top")
		(7 "B.SilkS" user "Ref Des/Silkscreen Bottom")
		(1 "F.Mask" user "Board Geometry/Soldermask Top")
		(3 "B.Mask" user "Board Geometry/Soldermask Bottom")
		(17 "Dwgs.User" user "User.Drawings")
		(19 "Cmts.User" user "User.Comments")
		(21 "Eco1.User" user "User.Eco1")
		(23 "Eco2.User" user "User.Eco2")
		(25 "Edge.Cuts" user "Board Geometry/Outline")
		(27 "Margin" user)
		(31 "F.CrtYd" user "Package Geometry/Place Bound Top")
		(29 "B.CrtYd" user "Package Geometry/Place Bound Bottom")
		(35 "F.Fab" user "Ref Des/Assembly Top")
		(33 "B.Fab" user "Ref Des/Assembly Bottom")
	)
	(footprint ""
		(layer "F.Cu")
		(at 276.126448 -25.432004 -90)
		(property "Reference" "C974"
			(at 0 0 270)
			(layer "F.SilkS")
			(hide yes)
			(effects
				(font
					(size 1.27 1.27)
				)
			)
		)
		(property "Value" ""
			(at 0 0 270)
			(layer "F.Fab")
			(effects
				(font
					(size 1.27 1.27)
				)
			)
		)
		(duplicate_pad_numbers_are_jumpers no)
		(fp_line
			(start -0.7874 0.4064)
			(end -0.7874 -0.4064)
			(stroke
				(width 0.1524)
				(type default)
			)
			(layer "F.SilkS")
		)
		(fp_line
			(start 0.7874 0.4064)
			(end -0.7874 0.4064)
			(stroke
				(width 0.1524)
				(type default)
			)
			(layer "F.SilkS")
		)
		(fp_line
			(start -0.7874 -0.4064)
			(end 0.7874 -0.4064)
			(stroke
				(width 0.1524)
				(type default)
			)
			(layer "F.SilkS")
		)
		(fp_line
			(start 0.7874 -0.4064)
			(end 0.7874 0.4064)
			(stroke
				(width 0.1524)
				(type default)
			)
			(layer "F.SilkS")
		)
		(fp_line
			(start -0.67945 0.3048)
			(end -0.67945 -0.305054)
			(stroke
				(width 0.1)
				(type default)
			)
			(layer "F.Fab")
		)
		(fp_line
			(start -0.12065 0.3048)
			(end -0.67945 0.3048)
			(stroke
				(width 0.1)
				(type default)
			)
			(layer "F.Fab")
		)
		(fp_line
			(start 0.120396 0.3048)
			(end 0.120396 0.2794)
			(stroke
				(width 0.1)
				(type default)
			)
			(layer "F.Fab")
		)
		(fp_line
			(start 0.67945 0.3048)
			(end 0.120396 0.3048)
			(stroke
				(width 0.1)
				(type default)
			)
			(layer "F.Fab")
		)
		(fp_line
			(start -0.12065 0.2794)
			(end -0.12065 0.3048)
			(stroke
				(width 0.1)
				(type default)
			)
			(layer "F.Fab")
		)
		(fp_line
			(start 0.120396 0.2794)
			(end -0.12065 0.2794)
			(stroke
				(width 0.1)
				(type default)
			)
			(layer "F.Fab")
		)
		(fp_line
			(start -0.12065 -0.2794)
			(end 0.12065 -0.2794)
			(stroke
				(width 0.1)
				(type default)
			)
			(layer "F.Fab")
		)
		(fp_line
			(start 0.12065 -0.2794)
			(end 0.12065 -0.3048)
			(stroke
				(width 0.1)
				(type default)
			)
			(layer "F.Fab")
		)
		(fp_line
			(start 0.12065 -0.3048)
			(end 0.67945 -0.3048)
			(stroke
				(width 0.1)
				(type default)
			)
			(layer "F.Fab")
		)
		(fp_line
			(start 0.67945 -0.3048)
			(end 0.67945 0.3048)
			(stroke
				(width 0.1)
				(type default)
			)
			(layer "F.Fab")
		)
		(fp_line
			(start -0.67945 -0.305054)
			(end -0.12065 -0.305054)
			(stroke
				(width 0.1)
				(type default)
			)
			(layer "F.Fab")
		)
		(fp_line
			(start -0.12065 -0.305054)
			(end -0.12065 -0.2794)
			(stroke
				(width 0.1)
				(type default)
			)
			(layer "F.Fab")
		)
		(pad "1" smd circle
			(at -0.40005 0 270)
			(size 0 0)
			(layers "F.Cu" "F.Mask" "F.Paste")
			(net "GND")
		)
		(pad "2" smd circle
			(at 0.40005 0 270)
			(size 0 0)
			(layers "F.Cu" "F.Mask" "F.Paste")
			(net "P3V3_SSD9")
		)
	)
	(footprint ""
		(layer "F.Cu")
		(at 389.81634 -356.244906 90)
		(property "Reference" "C742"
			(at 0 0 90)
			(layer "F.SilkS")
			(hide yes)
			(effects
				(font
					(size 1.27 1.27)
				)
			)
		)
		(property "Value" ""
			(at 0 0 90)
			(layer "F.Fab")
			(effects
				(font
					(size 1.27 1.27)
				)
			)
		)
		(duplicate_pad_numbers_are_jumpers no)
		(fp_line
			(start 0.299974 -0.150114)
			(end 0.299974 0.150114)
			(stroke
				(width 0.1)
				(type default)
			)
			(layer "F.Fab")
		)
		(fp_line
			(start -0.299974 -0.150114)
			(end 0.299974 -0.150114)
			(stroke
				(width 0.1)
				(type default)
			)
			(layer "F.Fab")
		)
		(fp_line
			(start 0.299974 0.150114)
			(end -0.299974 0.150114)
			(stroke
				(width 0.1)
				(type default)
			)
			(layer "F.Fab")
		)
		(fp_line
			(start -0.299974 0.150114)
			(end -0.299974 -0.150114)
			(stroke
				(width 0.1)
				(type default)
			)
			(layer "F.Fab")
		)
		(pad "1" smd rect
			(at -0.2667 0 90)
			(size 0.3048 0.381)
			(layers "F.Cu" "F.Mask" "F.Paste")
			(net "P5E_PEX3_STN5_TX_DP<89>")
		)
		(pad "2" smd rect
			(at 0.2667 0 90)
			(size 0.3048 0.381)
			(layers "F.Cu" "F.Mask" "F.Paste")
			(net "P5E_PEX3_STN5_TX_C_DP<89>")
		)
	)
	(footprint ""
		(layer "F.Cu")
		(at 83.109562 -350.098614 90)
		(property "Reference" "C149"
			(at 0 0 90)
			(layer "F.SilkS")
			(hide yes)
			(effects
				(font
					(size 1.27 1.27)
				)
			)
		)
		(property "Value" ""
			(at 0 0 90)
			(layer "F.Fab")
			(effects
				(font
					(size 1.27 1.27)
				)
			)
		)
		(duplicate_pad_numbers_are_jumpers no)
		(fp_line
			(start 0.299974 -0.150114)
			(end 0.299974 0.150114)
			(stroke
				(width 0.1)
				(type default)
			)
			(layer "F.Fab")
		)
		(fp_line
			(start -0.299974 -0.150114)
			(end 0.299974 -0.150114)
			(stroke
				(width 0.1)
				(type default)
			)
			(layer "F.Fab")
		)
		(fp_line
			(start 0.299974 0.150114)
			(end -0.299974 0.150114)
			(stroke
				(width 0.1)
				(type default)
			)
			(layer "F.Fab")
		)
		(fp_line
			(start -0.299974 0.150114)
			(end -0.299974 -0.150114)
			(stroke
				(width 0.1)
				(type default)
			)
			(layer "F.Fab")
		)
		(pad "1" smd rect
			(at -0.2667 0 90)
			(size 0.3048 0.381)
			(layers "F.Cu" "F.Mask" "F.Paste")
			(net "P5E_PEX0_STN6_TX_DP<101>")
		)
		(pad "2" smd rect
			(at 0.2667 0 90)
			(size 0.3048 0.381)
			(layers "F.Cu" "F.Mask" "F.Paste")
			(net "P5E_PEX0_STN6_TX_C_DP<101>")
		)
	)
	(footprint ""
		(layer "F.Cu")
		(at 225.413316 -123.520962 180)
		(property "Reference" "R5961"
			(at 0 0 180)
			(layer "F.SilkS")
			(hide yes)
			(effects
				(font
					(size 1.27 1.27)
				)
			)
		)
		(property "Value" ""
			(at 0 0 180)
			(layer "F.Fab")
			(effects
				(font
					(size 1.27 1.27)
				)
			)
		)
		(duplicate_pad_numbers_are_jumpers no)
		(fp_line
			(start 0.7874 0.4064)
			(end -0.7874 0.4064)
			(stroke
				(width 0.1524)
				(type default)
			)
			(layer "F.SilkS")
		)
		(fp_line
			(start 0.7874 -0.4064)
			(end 0.7874 0.4064)
			(stroke
				(width 0.1524)
				(type default)
			)
			(layer "F.SilkS")
		)
		(fp_line
			(start -0.7874 0.4064)
			(end -0.7874 -0.4064)
			(stroke
				(width 0.1524)
				(type default)
			)
			(layer "F.SilkS")
		)
		(fp_line
			(start -0.7874 -0.4064)
			(end 0.7874 -0.4064)
			(stroke
				(width 0.1524)
				(type default)
			)
			(layer "F.SilkS")
		)
		(fp_line
			(start 0.67945 0.3048)
			(end 0.120396 0.3048)
			(stroke
				(width 0.1)
				(type default)
			)
			(layer "F.Fab")
		)
		(fp_line
			(start 0.67945 -0.3048)
			(end 0.67945 0.3048)
			(stroke
				(width 0.1)
				(type default)
			)
			(layer "F.Fab")
		)
		(fp_line
			(start 0.12065 -0.2794)
			(end 0.12065 -0.3048)
			(stroke
				(width 0.1)
				(type default)
			)
			(layer "F.Fab")
		)
		(fp_line
			(start 0.12065 -0.3048)
			(end 0.67945 -0.3048)
			(stroke
				(width 0.1)
				(type default)
			)
			(layer "F.Fab")
		)
		(fp_line
			(start 0.120396 0.3048)
			(end 0.120396 0.2794)
			(stroke
				(width 0.1)
				(type default)
			)
			(layer "F.Fab")
		)
		(fp_line
			(start 0.120396 0.2794)
			(end -0.12065 0.2794)
			(stroke
				(width 0.1)
				(type default)
			)
			(layer "F.Fab")
		)
		(fp_line
			(start -0.12065 0.3048)
			(end -0.67945 0.3048)
			(stroke
				(width 0.1)
				(type default)
			)
			(layer "F.Fab")
		)
		(fp_line
			(start -0.12065 0.2794)
			(end -0.12065 0.3048)
			(stroke
				(width 0.1)
				(type default)
			)
			(layer "F.Fab")
		)
		(fp_line
			(start -0.12065 -0.2794)
			(end 0.12065 -0.2794)
			(stroke
				(width 0.1)
				(type default)
			)
			(layer "F.Fab")
		)
		(fp_line
			(start -0.12065 -0.305054)
			(end -0.12065 -0.2794)
			(stroke
				(width 0.1)
				(type default)
			)
			(layer "F.Fab")
		)
		(fp_line
			(start -0.67945 0.3048)
			(end -0.67945 -0.305054)
			(stroke
				(width 0.1)
				(type default)
			)
			(layer "F.Fab")
		)
		(fp_line
			(start -0.67945 -0.305054)
			(end -0.12065 -0.305054)
			(stroke
				(width 0.1)
				(type default)
			)
			(layer "F.Fab")
		)
		(pad "1" smd circle
			(at -0.40005 0 180)
			(size 0 0)
			(layers "F.Cu" "F.Mask" "F.Paste")
			(net "P5V_AUX")
		)
		(pad "2" smd circle
			(at 0.40005 0 180)
			(size 0 0)
			(layers "F.Cu" "F.Mask" "F.Paste")
			(net "P3V3_NIC3_PG_G2")
		)
	)
	(footprint ""
		(layer "F.Cu")
		(at 355.968808 -156.288994 -90)
		(property "Reference" "PR7048"
			(at 0 0 270)
			(layer "F.SilkS")
			(hide yes)
			(effects
				(font
					(size 1.27 1.27)
				)
			)
		)
		(property "Value" ""
			(at 0 0 270)
			(layer "F.Fab")
			(effects
				(font
					(size 1.27 1.27)
				)
			)
		)
		(duplicate_pad_numbers_are_jumpers no)
		(fp_line
			(start -0.7874 0.4064)
			(end -0.7874 -0.4064)
			(stroke
				(width 0.1524)
				(type default)
			)
			(layer "F.SilkS")
		)
		(fp_line
			(start 0.7874 0.4064)
			(end -0.7874 0.4064)
			(stroke
				(width 0.1524)
				(type default)
			)
			(layer "F.SilkS")
		)
		(fp_line
			(start -0.7874 -0.4064)
			(end 0.7874 -0.4064)
			(stroke
				(width 0.1524)
				(type default)
			)
			(layer "F.SilkS")
		)
		(fp_line
			(start 0.7874 -0.4064)
			(end 0.7874 0.4064)
			(stroke
				(width 0.1524)
				(type default)
			)
			(layer "F.SilkS")
		)
		(fp_line
			(start -0.67945 0.3048)
			(end -0.67945 -0.305054)
			(stroke
				(width 0.1)
				(type default)
			)
			(layer "F.Fab")
		)
		(fp_line
			(start -0.12065 0.3048)
			(end -0.67945 0.3048)
			(stroke
				(width 0.1)
				(type default)
			)
			(layer "F.Fab")
		)
		(fp_line
			(start 0.120396 0.3048)
			(end 0.120396 0.2794)
			(stroke
				(width 0.1)
				(type default)
			)
			(layer "F.Fab")
		)
		(fp_line
			(start 0.67945 0.3048)
			(end 0.120396 0.3048)
			(stroke
				(width 0.1)
				(type default)
			)
			(layer "F.Fab")
		)
		(fp_line
			(start -0.12065 0.2794)
			(end -0.12065 0.3048)
			(stroke
				(width 0.1)
				(type default)
			)
			(layer "F.Fab")
		)
		(fp_line
			(start 0.120396 0.2794)
			(end -0.12065 0.2794)
			(stroke
				(width 0.1)
				(type default)
			)
			(layer "F.Fab")
		)
		(fp_line
			(start -0.12065 -0.2794)
			(end 0.12065 -0.2794)
			(stroke
				(width 0.1)
				(type default)
			)
			(layer "F.Fab")
		)
		(fp_line
			(start 0.12065 -0.2794)
			(end 0.12065 -0.3048)
			(stroke
				(width 0.1)
				(type default)
			)
			(layer "F.Fab")
		)
		(fp_line
			(start 0.12065 -0.3048)
			(end 0.67945 -0.3048)
			(stroke
				(width 0.1)
				(type default)
			)
			(layer "F.Fab")
		)
		(fp_line
			(start 0.67945 -0.3048)
			(end 0.67945 0.3048)
			(stroke
				(width 0.1)
				(type default)
			)
			(layer "F.Fab")
		)
		(fp_line
			(start -0.67945 -0.305054)
			(end -0.12065 -0.305054)
			(stroke
				(width 0.1)
				(type default)
			)
			(layer "F.Fab")
		)
		(fp_line
			(start -0.12065 -0.305054)
			(end -0.12065 -0.2794)
			(stroke
				(width 0.1)
				(type default)
			)
			(layer "F.Fab")
		)
		(pad "1" smd circle
			(at -0.40005 0 270)
			(size 0 0)
			(layers "F.Cu" "F.Mask" "F.Paste")
			(net "P12V_NIC6_CO_OV_FB")
		)
		(pad "2" smd circle
			(at 0.40005 0 270)
			(size 0 0)
			(layers "F.Cu" "F.Mask" "F.Paste")
			(net "P12V_AUX")
		)
	)
	(footprint ""
		(layer "F.Cu")
		(at 400.264884 -5.999988)
		(property "Reference" "H64"
			(at -4.501388 -5.169154 0)
			(unlocked yes)
			(layer "F.SilkS")
			(effects
				(font
					(size 0.7874 0.5842)
					(thickness 0.1524)
				)
				(justify left)
			)
		)
		(property "Value" ""
			(at 0 0 0)
			(layer "F.Fab")
			(effects
				(font
					(size 1.27 1.27)
				)
			)
		)
		(duplicate_pad_numbers_are_jumpers no)
		(pad "1" thru_hole circle
			(at 0 0)
			(size 10.0076 10.0076)
			(drill 5.6134)
			(layers "*.Cu" "*.Mask")
			(remove_unused_layers no)
			(net "GND")
			(clearance -1.9431)
		)
	)
	(footprint ""
		(layer "F.Cu")
		(at 333.35214 -95.264224 90)
		(property "Reference" "R4449"
			(at 0 0 90)
			(layer "F.SilkS")
			(hide yes)
			(effects
				(font
					(size 1.27 1.27)
				)
			)
		)
		(property "Value" ""
			(at 0 0 90)
			(layer "F.Fab")
			(effects
				(font
					(size 1.27 1.27)
				)
			)
		)
		(duplicate_pad_numbers_are_jumpers no)
		(fp_line
			(start 0.7874 -0.4064)
			(end 0.7874 0.4064)
			(stroke
				(width 0.1524)
				(type default)
			)
			(layer "F.SilkS")
		)
		(fp_line
			(start -0.7874 -0.4064)
			(end 0.7874 -0.4064)
			(stroke
				(width 0.1524)
				(type default)
			)
			(layer "F.SilkS")
		)
		(fp_line
			(start 0.7874 0.4064)
			(end -0.7874 0.4064)
			(stroke
				(width 0.1524)
				(type default)
			)
			(layer "F.SilkS")
		)
		(fp_line
			(start -0.7874 0.4064)
			(end -0.7874 -0.4064)
			(stroke
				(width 0.1524)
				(type default)
			)
			(layer "F.SilkS")
		)
		(fp_line
			(start -0.12065 -0.305054)
			(end -0.12065 -0.2794)
			(stroke
				(width 0.1)
				(type default)
			)
			(layer "F.Fab")
		)
		(fp_line
			(start -0.67945 -0.305054)
			(end -0.12065 -0.305054)
			(stroke
				(width 0.1)
				(type default)
			)
			(layer "F.Fab")
		)
		(fp_line
			(start 0.67945 -0.3048)
			(end 0.67945 0.3048)
			(stroke
				(width 0.1)
				(type default)
			)
			(layer "F.Fab")
		)
		(fp_line
			(start 0.12065 -0.3048)
			(end 0.67945 -0.3048)
			(stroke
				(width 0.1)
				(type default)
			)
			(layer "F.Fab")
		)
		(fp_line
			(start 0.12065 -0.2794)
			(end 0.12065 -0.3048)
			(stroke
				(width 0.1)
				(type default)
			)
			(layer "F.Fab")
		)
		(fp_line
			(start -0.12065 -0.2794)
			(end 0.12065 -0.2794)
			(stroke
				(width 0.1)
				(type default)
			)
			(layer "F.Fab")
		)
		(fp_line
			(start 0.120396 0.2794)
			(end -0.12065 0.2794)
			(stroke
				(width 0.1)
				(type default)
			)
			(layer "F.Fab")
		)
		(fp_line
			(start -0.12065 0.2794)
			(end -0.12065 0.3048)
			(stroke
				(width 0.1)
				(type default)
			)
			(layer "F.Fab")
		)
		(fp_line
			(start 0.67945 0.3048)
			(end 0.120396 0.3048)
			(stroke
				(width 0.1)
				(type default)
			)
			(layer "F.Fab")
		)
		(fp_line
			(start 0.120396 0.3048)
			(end 0.120396 0.2794)
			(stroke
				(width 0.1)
				(type default)
			)
			(layer "F.Fab")
		)
		(fp_line
			(start -0.12065 0.3048)
			(end -0.67945 0.3048)
			(stroke
				(width 0.1)
				(type default)
			)
			(layer "F.Fab")
		)
		(fp_line
			(start -0.67945 0.3048)
			(end -0.67945 -0.305054)
			(stroke
				(width 0.1)
				(type default)
			)
			(layer "F.Fab")
		)
		(pad "1" smd circle
			(at -0.40005 0 90)
			(size 0 0)
			(layers "F.Cu" "F.Mask" "F.Paste")
			(net "HP_NIC5_EN")
		)
		(pad "2" smd circle
			(at 0.40005 0 90)
			(size 0 0)
			(layers "F.Cu" "F.Mask" "F.Paste")
			(net "P12V_NIC5_EN_R")
		)
	)
	(footprint ""
		(layer "F.Cu")
		(at 55.88 -142.9512)
		(property "Reference" "R9"
			(at 0 0 0)
			(layer "F.SilkS")
			(hide yes)
			(effects
				(font
					(size 1.27 1.27)
				)
			)
		)
		(property "Value" ""
			(at 0 0 0)
			(layer "F.Fab")
			(effects
				(font
					(size 1.27 1.27)
				)
			)
		)
		(duplicate_pad_numbers_are_jumpers no)
		(fp_line
			(start -0.7874 -0.4064)
			(end 0.7874 -0.4064)
			(stroke
				(width 0.1524)
				(type default)
			)
			(layer "F.SilkS")
		)
		(fp_line
			(start -0.7874 0.4064)
			(end -0.7874 -0.4064)
			(stroke
				(width 0.1524)
				(type default)
			)
			(layer "F.SilkS")
		)
		(fp_line
			(start 0.7874 -0.4064)
			(end 0.7874 0.4064)
			(stroke
				(width 0.1524)
				(type default)
			)
			(layer "F.SilkS")
		)
		(fp_line
			(start 0.7874 0.4064)
			(end -0.7874 0.4064)
			(stroke
				(width 0.1524)
				(type default)
			)
			(layer "F.SilkS")
		)
		(fp_line
			(start -0.67945 -0.305054)
			(end -0.12065 -0.305054)
			(stroke
				(width 0.1)
				(type default)
			)
			(layer "F.Fab")
		)
		(fp_line
			(start -0.67945 0.3048)
			(end -0.67945 -0.305054)
			(stroke
				(width 0.1)
				(type default)
			)
			(layer "F.Fab")
		)
		(fp_line
			(start -0.12065 -0.305054)
			(end -0.12065 -0.2794)
			(stroke
				(width 0.1)
				(type default)
			)
			(layer "F.Fab")
		)
		(fp_line
			(start -0.12065 -0.2794)
			(end 0.12065 -0.2794)
			(stroke
				(width 0.1)
				(type default)
			)
			(layer "F.Fab")
		)
		(fp_line
			(start -0.12065 0.2794)
			(end -0.12065 0.3048)
			(stroke
				(width 0.1)
				(type default)
			)
			(layer "F.Fab")
		)
		(fp_line
			(start -0.12065 0.3048)
			(end -0.67945 0.3048)
			(stroke
				(width 0.1)
				(type default)
			)
			(layer "F.Fab")
		)
		(fp_line
			(start 0.120396 0.2794)
			(end -0.12065 0.2794)
			(stroke
				(width 0.1)
				(type default)
			)
			(layer "F.Fab")
		)
		(fp_line
			(start 0.120396 0.3048)
			(end 0.120396 0.2794)
			(stroke
				(width 0.1)
				(type default)
			)
			(layer "F.Fab")
		)
		(fp_line
			(start 0.12065 -0.3048)
			(end 0.67945 -0.3048)
			(stroke
				(width 0.1)
				(type default)
			)
			(layer "F.Fab")
		)
		(fp_line
			(start 0.12065 -0.2794)
			(end 0.12065 -0.3048)
			(stroke
				(width 0.1)
				(type default)
			)
			(layer "F.Fab")
		)
		(fp_line
			(start 0.67945 -0.3048)
			(end 0.67945 0.3048)
			(stroke
				(width 0.1)
				(type default)
			)
			(layer "F.Fab")
		)
		(fp_line
			(start 0.67945 0.3048)
			(end 0.120396 0.3048)
			(stroke
				(width 0.1)
				(type default)
			)
			(layer "F.Fab")
		)
		(pad "1" smd circle
			(at -0.40005 0)
			(size 0 0)
			(layers "F.Cu" "F.Mask" "F.Paste")
			(net "SMB_NIC0_R_SCL")
		)
		(pad "2" smd circle
			(at 0.40005 0)
			(size 0 0)
			(layers "F.Cu" "F.Mask" "F.Paste")
			(net "P3V3_NIC0")
		)
	)
)
